# BASEBOARD_FAB2 (Tioga Pass) — schematic netlist excerpt (pin names and nets, part order shuffled) for the footprints in the layout excerpt that follows; sources: Cadence DE-HDL packaged netlist, KiCad conversion of Wiwynn_Tioga_Pass_MB.brd

R7B20  RES  0.0 5% CHIP  pkg 0402  page 232 : A = GND ; B = AGND_PVPP_DEF
C5L14  CAP  100UF 4V 20% X5R  pkg 0805  page 220 : A = PVDDQ_DEF ; B = GND
R2U30  RES  4.75K 1% EMPTY  pkg 0402  page 125 : A = P3V3_STBY ; B = FM_UV_ADR_TRIGGER_EN

(kicad_pcb
	(version 20260206)
	(generator "pcbnew")
	(generator_version "10.0")
	(general
		(thickness 1.6)
		(legacy_teardrops no)
	)
	(paper "A4")
	(title_block
		(title "Wiwynn_Tioga_Pass_MB.brd")
		(comment 1 "Tioga Pass / footprints 3506-3508 of 4770")
	)
	(layers
		(0 "F.Cu" signal "TOP")
		(4 "In1.Cu" signal "L2GND")
		(6 "In2.Cu" signal "L3")
		(8 "In3.Cu" signal "L4GND")
		(10 "In4.Cu" signal "L5")
		(12 "In5.Cu" signal "L6GND")
		(14 "In6.Cu" signal "L7VCC")
		(16 "In7.Cu" signal "L8VCC")
		(18 "In8.Cu" signal "L9GND")
		(20 "In9.Cu" signal "L10")
		(22 "In10.Cu" signal "L11GND")
		(24 "In11.Cu" signal "L12")
		(26 "In12.Cu" signal "L13GND")
		(2 "B.Cu" signal "BOTTOM")
		(9 "F.Adhes" user "F.Adhesive")
		(11 "B.Adhes" user "B.Adhesive")
		(13 "F.Paste" user "Package Geometry/Pastemask Top")
		(15 "B.Paste" user "Package Geometry/Pastemask Bottom")
		(5 "F.SilkS" user "Ref Des/Silkscreen Top")
		(7 "B.SilkS" user "Ref Des/Silkscreen Bottom")
		(1 "F.Mask" user "Board Geometry/Soldermask Top")
		(3 "B.Mask" user "Board Geometry/Soldermask Bottom")
		(17 "Dwgs.User" user "User.Drawings")
		(19 "Cmts.User" user "User.Comments")
		(21 "Eco1.User" user "User.Eco1")
		(23 "Eco2.User" user "User.Eco2")
		(25 "Edge.Cuts" user "Board Geometry/Outline")
		(27 "Margin" user)
		(31 "F.CrtYd" user "Package Geometry/Place Bound Top")
		(29 "B.CrtYd" user "Package Geometry/Place Bound Bottom")
		(35 "F.Fab" user "Ref Des/Assembly Top")
		(33 "B.Fab" user "Ref Des/Assembly Bottom")
	)
	(footprint ""
		(layer "B.Cu")
		(at 259.4102 -144.977612 90)
		(property "Reference" "C5L14"
			(at 0 0 90)
			(layer "B.SilkS")
			(hide yes)
			(effects
				(font
					(size 1.27 1.27)
				)
				(justify mirror)
			)
		)
		(property "Value" ""
			(at 0 0 90)
			(layer "B.Fab")
			(effects
				(font
					(size 1.27 1.27)
				)
				(justify mirror)
			)
		)
		(duplicate_pad_numbers_are_jumpers no)
		(fp_rect
			(start -0.7239 -0.2159)
			(end 0.7239 1.9939)
			(stroke
				(width 0)
				(type default)
			)
			(fill no)
			(layer "B.CrtYd")
		)
		(fp_line
			(start 0.7239 -0.2159)
			(end 0.7239 1.9939)
			(stroke
				(width 0.1)
				(type default)
			)
			(layer "B.Fab")
		)
		(fp_line
			(start -0.7239 -0.2159)
			(end 0.7239 -0.2159)
			(stroke
				(width 0.1)
				(type default)
			)
			(layer "B.Fab")
		)
		(fp_line
			(start 0.7239 1.9939)
			(end -0.7239 1.9939)
			(stroke
				(width 0.1)
				(type default)
			)
			(layer "B.Fab")
		)
		(fp_line
			(start -0.7239 1.9939)
			(end -0.7239 -0.2159)
			(stroke
				(width 0.1)
				(type default)
			)
			(layer "B.Fab")
		)
		(pad "1" smd rect
			(at 0 0 270)
			(size 1.27 1.016)
			(layers "B.Cu" "B.Mask" "B.Paste")
			(net "PVDDQ_DEF")
		)
		(pad "2" smd rect
			(at 0 1.778 270)
			(size 1.27 1.016)
			(layers "B.Cu" "B.Mask" "B.Paste")
			(net "GND")
		)
		(zone
			(layer "B.Cu")
			(hatch none 0.5)
			(connect_pads
				(clearance 0)
			)
			(min_thickness 0.25)
			(keepout
				(tracks not_allowed)
				(vias allowed)
				(pads allowed)
				(copperpour not_allowed)
				(footprints allowed)
			)
			(placement
				(enabled no)
				(sheetname "")
			)
			(fill
				(thermal_gap 0.5)
				(thermal_bridge_width 0.5)
				(island_removal_mode 0)
			)
			(polygon
				(pts
					(xy 259.9182 -144.342612) (xy 260.6802 -144.342612) (xy 260.6802 -145.612612) (xy 259.9182 -145.612612)
				)
			)
		)
	)
	(footprint ""
		(layer "B.Cu")
		(at 343.248234 -130.120898 90)
		(property "Reference" "R7B20"
			(at 0 0 90)
			(layer "B.SilkS")
			(hide yes)
			(effects
				(font
					(size 1.27 1.27)
				)
				(justify mirror)
			)
		)
		(property "Value" ""
			(at 0 0 90)
			(layer "B.Fab")
			(effects
				(font
					(size 1.27 1.27)
				)
				(justify mirror)
			)
		)
		(duplicate_pad_numbers_are_jumpers no)
		(fp_poly
			(pts
				(xy 0.2794 -0.1016) (xy -0.2794 -0.1016) (xy -0.2794 0.9906) (xy 0.2794 0.9906)
			)
			(stroke
				(width 0)
				(type default)
			)
			(fill no)
			(layer "B.CrtYd")
		)
		(fp_line
			(start 0.2794 -0.1016)
			(end 0.2794 0.9906)
			(stroke
				(width 0.1)
				(type default)
			)
			(layer "B.Fab")
		)
		(fp_line
			(start -0.2794 -0.1016)
			(end 0.2794 -0.1016)
			(stroke
				(width 0.1)
				(type default)
			)
			(layer "B.Fab")
		)
		(fp_line
			(start 0.2794 0.9906)
			(end -0.2794 0.9906)
			(stroke
				(width 0.1)
				(type default)
			)
			(layer "B.Fab")
		)
		(fp_line
			(start -0.2794 0.9906)
			(end -0.2794 -0.1016)
			(stroke
				(width 0.1)
				(type default)
			)
			(layer "B.Fab")
		)
		(pad "1" smd rect
			(at 0 0 270)
			(size 0.508 0.508)
			(layers "B.Cu" "B.Mask" "B.Paste")
			(net "GND")
		)
		(pad "2" smd rect
			(at 0 0.889 270)
			(size 0.508 0.508)
			(layers "B.Cu" "B.Mask" "B.Paste")
			(net "AGND_PVPP_DEF")
		)
		(zone
			(layer "B.Cu")
			(hatch none 0.5)
			(connect_pads
				(clearance 0)
			)
			(min_thickness 0.25)
			(keepout
				(tracks allowed)
				(vias not_allowed)
				(pads allowed)
				(copperpour not_allowed)
				(footprints allowed)
			)
			(placement
				(enabled no)
				(sheetname "")
			)
			(fill
				(thermal_gap 0.5)
				(thermal_bridge_width 0.5)
				(island_removal_mode 0)
			)
			(polygon
				(pts
					(xy 343.502234 -130.374898) (xy 343.502234 -129.866898) (xy 343.883234 -129.866898) (xy 343.883234 -130.374898)
				)
			)
		)
		(zone
			(layer "B.Cu")
			(hatch none 0.5)
			(connect_pads
				(clearance 0)
			)
			(min_thickness 0.25)
			(keepout
				(tracks not_allowed)
				(vias allowed)
				(pads allowed)
				(copperpour not_allowed)
				(footprints allowed)
			)
			(placement
				(enabled no)
				(sheetname "")
			)
			(fill
				(thermal_gap 0.5)
				(thermal_bridge_width 0.5)
				(island_removal_mode 0)
			)
			(polygon
				(pts
					(xy 343.883234 -130.374898) (xy 343.883234 -129.866898) (xy 343.502234 -129.866898) (xy 343.502234 -130.374898)
				)
			)
		)
	)
	(footprint ""
		(layer "B.Cu")
		(at 405.219408 -94.517718 -90)
		(property "Reference" "R2U30"
			(at 0 0 90)
			(layer "B.SilkS")
			(hide yes)
			(effects
				(font
					(size 1.27 1.27)
				)
				(justify mirror)
			)
		)
		(property "Value" ""
			(at 0 0 90)
			(layer "B.Fab")
			(effects
				(font
					(size 1.27 1.27)
				)
				(justify mirror)
			)
		)
		(duplicate_pad_numbers_are_jumpers no)
		(fp_poly
			(pts
				(xy 0.2794 -0.1016) (xy -0.2794 -0.1016) (xy -0.2794 0.9906) (xy 0.2794 0.9906)
			)
			(stroke
				(width 0)
				(type default)
			)
			(fill no)
			(layer "B.CrtYd")
		)
		(fp_line
			(start -0.2794 0.9906)
			(end -0.2794 -0.1016)
			(stroke
				(width 0.1)
				(type default)
			)
			(layer "B.Fab")
		)
		(fp_line
			(start 0.2794 0.9906)
			(end -0.2794 0.9906)
			(stroke
				(width 0.1)
				(type default)
			)
			(layer "B.Fab")
		)
		(fp_line
			(start -0.2794 -0.1016)
			(end 0.2794 -0.1016)
			(stroke
				(width 0.1)
				(type default)
			)
			(layer "B.Fab")
		)
		(fp_line
			(start 0.2794 -0.1016)
			(end 0.2794 0.9906)
			(stroke
				(width 0.1)
				(type default)
			)
			(layer "B.Fab")
		)
		(pad "1" smd rect
			(at 0 0 90)
			(size 0.508 0.508)
			(layers "B.Cu" "B.Mask" "B.Paste")
			(net "P3V3_STBY")
		)
		(pad "2" smd rect
			(at 0 0.889 90)
			(size 0.508 0.508)
			(layers "B.Cu" "B.Mask" "B.Paste")
			(net "FM_UV_ADR_TRIGGER_EN")
		)
		(zone
			(layer "B.Cu")
			(hatch none 0.5)
			(connect_pads
				(clearance 0)
			)
			(min_thickness 0.25)
			(keepout
				(tracks not_allowed)
				(vias allowed)
				(pads allowed)
				(copperpour not_allowed)
				(footprints allowed)
			)
			(placement
				(enabled no)
				(sheetname "")
			)
			(fill
				(thermal_gap 0.5)
				(thermal_bridge_width 0.5)
				(island_removal_mode 0)
			)
			(polygon
				(pts
					(xy 404.584408 -94.263718) (xy 404.584408 -94.771718) (xy 404.965408 -94.771718) (xy 404.965408 -94.263718)
				)
			)
		)
		(zone
			(layer "B.Cu")
			(hatch none 0.5)
			(connect_pads
				(clearance 0)
			)
			(min_thickness 0.25)
			(keepout
				(tracks allowed)
				(vias not_allowed)
				(pads allowed)
				(copperpour not_allowed)
				(footprints allowed)
			)
			(placement
				(enabled no)
				(sheetname "")
			)
			(fill
				(thermal_gap 0.5)
				(thermal_bridge_width 0.5)
				(island_removal_mode 0)
			)
			(polygon
				(pts
					(xy 404.965408 -94.263718) (xy 404.965408 -94.771718) (xy 404.584408 -94.771718) (xy 404.584408 -94.263718)
				)
			)
		)
	)
)
